(kicad_sch
	(version 20250114)
	(generator "eeschema")
	(generator_version "9.0")
	(paper "A3")
	(title_block
		(title "LPDDR4 testbed")
		(date "2024-03-26")
		(rev "1.2.2")
	)
	(text "LPDDR4 testbed"
		(exclude_from_sim no)
		(at 18.415 21.59 0)
		(effects
			(font
				(size 2.4892 2.4892)
				(thickness 0.4978)
				(bold yes)
			)
			(justify left bottom)
		)
	)
	(sheet
		(at 194.945 150.495)
		(size 41.91 28.575)
		(exclude_from_sim no)
		(in_bom yes)
		(on_board yes)
		(dnp no)
		(fields_autoplaced yes)
		(stroke
			(width 0)
			(type solid)
		)
		(fill
			(color 0 0 0 0.0000)
		)
		(property "Sheetname" "SODIMM"
			(at 194.945 149.7834 0)
			(effects
				(font
					(size 1.27 1.27)
				)
				(justify left bottom)
			)
		)
		(property "Sheetfile" "sodim.kicad_sch"
			(at 194.945 179.6546 0)
			(effects
				(font
					(size 1.27 1.27)
				)
				(justify left top)
			)
		)
		(instances
			(project "lpddr4-testbed"
				(path ""
					(page "3")
				)
			)
		)
	)
	(sheet
		(at 254.635 149.86)
		(size 41.91 28.575)
		(exclude_from_sim no)
		(in_bom yes)
		(on_board yes)
		(dnp no)
		(fields_autoplaced yes)
		(stroke
			(width 0)
			(type solid)
		)
		(fill
			(color 0 0 0 0.0000)
		)
		(property "Sheetname" "LPDDR4"
			(at 254.635 149.1484 0)
			(effects
				(font
					(size 1.27 1.27)
				)
				(justify left bottom)
			)
		)
		(property "Sheetfile" "lpddr4.kicad_sch"
			(at 254.635 179.0196 0)
			(effects
				(font
					(size 1.27 1.27)
				)
				(justify left top)
			)
		)
		(instances
			(project "lpddr4-testbed"
				(path ""
					(page "4")
				)
			)
		)
	)
	(sheet
		(at 137.16 151.13)
		(size 40.64 27.94)
		(exclude_from_sim no)
		(in_bom yes)
		(on_board yes)
		(dnp no)
		(fields_autoplaced yes)
		(stroke
			(width 0)
			(type solid)
		)
		(fill
			(color 0 0 0 0.0000)
		)
		(property "Sheetname" "EEPROM"
			(at 137.16 150.4184 0)
			(effects
				(font
					(size 1.27 1.27)
				)
				(justify left bottom)
			)
		)
		(property "Sheetfile" "EEPROM.kicad_sch"
			(at 137.16 179.6546 0)
			(effects
				(font
					(size 1.27 1.27)
				)
				(justify left top)
			)
		)
		(instances
			(project "lpddr4-testbed"
				(path ""
					(page "2")
				)
			)
		)
	)
	(sheet_instances
		(path "/"
			(page "1")
		)
	)
)
